# BASEBOARD_FAB2 (Tioga Pass) — schematic netlist excerpt (pin names and nets, part order shuffled) for the footprints in the layout excerpt that follows; sources: Cadence DE-HDL packaged netlist, KiCad conversion of Wiwynn_Tioga_Pass_MB.brd

R25W10  120R2F-GP  1%  pkg RCL_GP  page 151 : \1\ = GND ; \2\ = BMC_M_BA1
C3N31  CAP_A  22.0UF 4V 20% X6S  pkg 0603V  page 132 : A = PVNN_PCH_STBY ; B = GND
C3N26  CAPP  470UF 2.5V 20% ALUM  pkg 3018  page 212 : A = PVCCIO_CPU0 ; B = GND

(kicad_pcb
	(version 20260206)
	(generator "pcbnew")
	(generator_version "10.0")
	(general
		(thickness 1.6)
		(legacy_teardrops no)
	)
	(paper "A4")
	(title_block
		(title "Wiwynn_Tioga_Pass_MB.brd")
		(comment 1 "Tioga Pass / footprints 4683-4685 of 4770")
	)
	(layers
		(0 "F.Cu" signal "TOP")
		(4 "In1.Cu" signal "L2GND")
		(6 "In2.Cu" signal "L3")
		(8 "In3.Cu" signal "L4GND")
		(10 "In4.Cu" signal "L5")
		(12 "In5.Cu" signal "L6GND")
		(14 "In6.Cu" signal "L7VCC")
		(16 "In7.Cu" signal "L8VCC")
		(18 "In8.Cu" signal "L9GND")
		(20 "In9.Cu" signal "L10")
		(22 "In10.Cu" signal "L11GND")
		(24 "In11.Cu" signal "L12")
		(26 "In12.Cu" signal "L13GND")
		(2 "B.Cu" signal "BOTTOM")
		(9 "F.Adhes" user "F.Adhesive")
		(11 "B.Adhes" user "B.Adhesive")
		(13 "F.Paste" user "Package Geometry/Pastemask Top")
		(15 "B.Paste" user "Package Geometry/Pastemask Bottom")
		(5 "F.SilkS" user "Ref Des/Silkscreen Top")
		(7 "B.SilkS" user "Ref Des/Silkscreen Bottom")
		(1 "F.Mask" user "Board Geometry/Soldermask Top")
		(3 "B.Mask" user "Board Geometry/Soldermask Bottom")
		(17 "Dwgs.User" user "User.Drawings")
		(19 "Cmts.User" user "User.Comments")
		(21 "Eco1.User" user "User.Eco1")
		(23 "Eco2.User" user "User.Eco2")
		(25 "Edge.Cuts" user "Board Geometry/Outline")
		(27 "Margin" user)
		(31 "F.CrtYd" user "Package Geometry/Place Bound Top")
		(29 "B.CrtYd" user "Package Geometry/Place Bound Bottom")
		(35 "F.Fab" user "Ref Des/Assembly Top")
		(33 "B.Fab" user "Ref Des/Assembly Bottom")
	)
	(footprint ""
		(layer "B.Cu")
		(at 336.042 -104.394 90)
		(property "Reference" "C3N26"
			(at 1.24333 -3.81 0)
			(unlocked yes)
			(layer "B.SilkS")
			(effects
				(font
					(size 0.7874 0.5842)
					(thickness 0.1524)
				)
				(justify mirror)
			)
		)
		(property "Value" ""
			(at 0 0 90)
			(layer "B.Fab")
			(effects
				(font
					(size 1.27 1.27)
				)
				(justify mirror)
			)
		)
		(duplicate_pad_numbers_are_jumpers no)
		(fp_line
			(start 2.563114 -1.616456)
			(end 2.563114 1.633728)
			(stroke
				(width 0.1524)
				(type default)
			)
			(layer "B.SilkS")
		)
		(fp_line
			(start 1.6002 -1.616456)
			(end 2.563114 -1.616456)
			(stroke
				(width 0.1524)
				(type default)
			)
			(layer "B.SilkS")
		)
		(fp_line
			(start -1.6002 -1.616456)
			(end -2.504948 -1.616456)
			(stroke
				(width 0.1524)
				(type default)
			)
			(layer "B.SilkS")
		)
		(fp_line
			(start -2.504948 -1.616456)
			(end -2.504948 1.633728)
			(stroke
				(width 0.1524)
				(type default)
			)
			(layer "B.SilkS")
		)
		(fp_line
			(start 2.563114 1.633728)
			(end 1.6002 1.633728)
			(stroke
				(width 0.1524)
				(type default)
			)
			(layer "B.SilkS")
		)
		(fp_line
			(start -2.504948 1.633728)
			(end -1.6002 1.633728)
			(stroke
				(width 0.1524)
				(type default)
			)
			(layer "B.SilkS")
		)
		(fp_line
			(start 2.286 7.366)
			(end 2.286 1.632712)
			(stroke
				(width 0.1524)
				(type default)
			)
			(layer "B.SilkS")
		)
		(fp_line
			(start 2.286 7.366)
			(end 1.60147 7.366)
			(stroke
				(width 0.1524)
				(type default)
			)
			(layer "B.SilkS")
		)
		(fp_line
			(start -2.286 7.366)
			(end -2.286 1.63195)
			(stroke
				(width 0.1524)
				(type default)
			)
			(layer "B.SilkS")
		)
		(fp_line
			(start -2.286 7.366)
			(end -1.600708 7.366)
			(stroke
				(width 0.1524)
				(type default)
			)
			(layer "B.SilkS")
		)
		(fp_rect
			(start 2.286 7.366)
			(end -2.286 -0.254)
			(stroke
				(width 0)
				(type default)
			)
			(fill no)
			(layer "B.CrtYd")
		)
		(fp_line
			(start 2.286 -0.254)
			(end -2.286 -0.254)
			(stroke
				(width 0.1)
				(type default)
			)
			(layer "B.Fab")
		)
		(fp_line
			(start -2.286 -0.254)
			(end -2.286 7.366)
			(stroke
				(width 0.1)
				(type default)
			)
			(layer "B.Fab")
		)
		(fp_line
			(start 2.286 7.366)
			(end 2.286 -0.254)
			(stroke
				(width 0.1)
				(type default)
			)
			(layer "B.Fab")
		)
		(fp_line
			(start -2.286 7.366)
			(end 2.286 7.366)
			(stroke
				(width 0.1)
				(type default)
			)
			(layer "B.Fab")
		)
		(pad "1" smd rect
			(at 0 0 270)
			(size 2.54 3.048)
			(layers "B.Cu" "B.Mask" "B.Paste")
			(net "PVCCIO_CPU0")
		)
		(pad "2" smd rect
			(at 0 7.112 270)
			(size 2.54 3.048)
			(layers "B.Cu" "B.Mask" "B.Paste")
			(net "GND")
		)
	)
	(footprint ""
		(layer "B.Cu")
		(at 368.184938 -102.18039 -90)
		(property "Reference" "C3N31"
			(at 0 0 90)
			(layer "B.SilkS")
			(hide yes)
			(effects
				(font
					(size 1.27 1.27)
				)
				(justify mirror)
			)
		)
		(property "Value" ""
			(at 0 0 90)
			(layer "B.Fab")
			(effects
				(font
					(size 1.27 1.27)
				)
				(justify mirror)
			)
		)
		(duplicate_pad_numbers_are_jumpers no)
		(fp_poly
			(pts
				(xy 0.4953 -0.2032) (xy -0.4953 -0.2032) (xy -0.4953 1.6002) (xy 0.4953 1.6002)
			)
			(stroke
				(width 0)
				(type default)
			)
			(fill no)
			(layer "B.CrtYd")
		)
		(fp_line
			(start -0.4953 1.6002)
			(end 0.4953 1.6002)
			(stroke
				(width 0.1)
				(type default)
			)
			(layer "B.Fab")
		)
		(fp_line
			(start 0.4953 1.6002)
			(end 0.4953 -0.2032)
			(stroke
				(width 0.1)
				(type default)
			)
			(layer "B.Fab")
		)
		(fp_line
			(start -0.4953 -0.2032)
			(end -0.4953 1.6002)
			(stroke
				(width 0.1)
				(type default)
			)
			(layer "B.Fab")
		)
		(fp_line
			(start 0.4953 -0.2032)
			(end -0.4953 -0.2032)
			(stroke
				(width 0.1)
				(type default)
			)
			(layer "B.Fab")
		)
		(pad "1" smd rect
			(at 0 0 90)
			(size 0.762 0.889)
			(layers "B.Cu" "B.Mask" "B.Paste")
			(net "PVNN_PCH_STBY")
		)
		(pad "2" smd rect
			(at 0 1.397 90)
			(size 0.762 0.889)
			(layers "B.Cu" "B.Mask" "B.Paste")
			(net "GND")
		)
		(zone
			(layer "B.Cu")
			(hatch none 0.5)
			(connect_pads
				(clearance 0)
			)
			(min_thickness 0.25)
			(keepout
				(tracks not_allowed)
				(vias allowed)
				(pads allowed)
				(copperpour not_allowed)
				(footprints allowed)
			)
			(placement
				(enabled no)
				(sheetname "")
			)
			(fill
				(thermal_gap 0.5)
				(thermal_bridge_width 0.5)
				(island_removal_mode 0)
			)
			(polygon
				(pts
					(xy 367.740438 -101.79939) (xy 367.740438 -102.56139) (xy 367.232438 -102.56139) (xy 367.232438 -101.79939)
				)
			)
		)
	)
	(footprint ""
		(layer "B.Cu")
		(at 438.833006 -41.648126 180)
		(property "Reference" "R25W10"
			(at 0 0 0)
			(layer "B.SilkS")
			(hide yes)
			(effects
				(font
					(size 1.27 1.27)
				)
				(justify mirror)
			)
		)
		(property "Value" "*"
			(at -0.064008 -4.108196 180)
			(unlocked yes)
			(layer "B.Fab")
			(hide yes)
			(effects
				(font
					(size 1.27 1.016)
					(thickness 0.1524)
				)
				(justify mirror)
			)
		)
		(property "Device Type" "120R2F-GP_RCL_GP-120R2F-GP,64.A"
			(at -0.064008 -5.632196 180)
			(unlocked yes)
			(layer "B.Fab")
			(hide yes)
			(effects
				(font
					(size 1.27 1.016)
					(thickness 0.1524)
				)
				(justify mirror)
			)
		)
		(duplicate_pad_numbers_are_jumpers no)
		(fp_line
			(start 0.508 -0.9398)
			(end 0.508 0.9398)
			(stroke
				(width 0.1524)
				(type default)
			)
			(layer "B.SilkS")
		)
		(fp_line
			(start -0.508 -0.9398)
			(end 0.508 -0.9398)
			(stroke
				(width 0.1524)
				(type default)
			)
			(layer "B.SilkS")
		)
		(fp_rect
			(start 0.508 0.9398)
			(end -0.508 -0.9398)
			(stroke
				(width 0)
				(type default)
			)
			(fill no)
			(layer "B.CrtYd")
		)
		(fp_rect
			(start 0.508 0.9398)
			(end -0.508 -0.9398)
			(stroke
				(width 0)
				(type default)
			)
			(fill no)
			(layer "B.Fab")
		)
		(pad "1" smd custom
			(at 0 -0.4445)
			(size 0.1397 0.1397)
			(layers "B.Cu" "B.Mask" "B.Paste")
			(net "GND")
			(options
				(clearance outline)
				(anchor circle)
			)
			(primitives
				(gr_poly
					(pts
						(arc
							(start -0.1778 0.2794)
							(mid -0.249642 0.249642)
							(end -0.2794 0.1778)
						)
						(arc
							(start -0.2794 -0.1778)
							(mid -0.249642 -0.249642)
							(end -0.1778 -0.2794)
						)
						(arc
							(start 0.1778 -0.2794)
							(mid 0.249642 -0.249642)
							(end 0.2794 -0.1778)
						)
						(arc
							(start 0.2794 0.1778)
							(mid 0.249642 0.249642)
							(end 0.1778 0.2794)
						)
					)
					(width 0)
					(fill yes)
				)
			)
		)
		(pad "2" smd custom
			(at 0 0.4445)
			(size 0.1397 0.1397)
			(layers "B.Cu" "B.Mask" "B.Paste")
			(net "BMC_M_BA1")
			(options
				(clearance outline)
				(anchor circle)
			)
			(primitives
				(gr_poly
					(pts
						(arc
							(start -0.1778 0.2794)
							(mid -0.249642 0.249642)
							(end -0.2794 0.1778)
						)
						(arc
							(start -0.2794 -0.1778)
							(mid -0.249642 -0.249642)
							(end -0.1778 -0.2794)
						)
						(arc
							(start 0.1778 -0.2794)
							(mid 0.249642 -0.249642)
							(end 0.2794 -0.1778)
						)
						(arc
							(start 0.2794 0.1778)
							(mid 0.249642 0.249642)
							(end 0.1778 0.2794)
						)
					)
					(width 0)
					(fill yes)
				)
			)
		)
	)
)
